(kicad_pcb
	(version 20260206)
	(generator "pcbnew")
	(generator_version "10.0")
	(general
		(thickness 1.6)
		(legacy_teardrops no)
	)
	(paper "A4")
	(title_block
		(title "01162023_DA0F0TEBIF0_F0T_Expander_BD_F_brd_V02_OCP.brd")
		(comment 1 "Grand Teton / footprints 6355-6362 of 9728")
	)
	(layers
		(0 "F.Cu" signal "TOP")
		(4 "In1.Cu" signal "GND")
		(6 "In2.Cu" signal "VCC")
		(8 "In3.Cu" signal "VCC1")
		(10 "In4.Cu" signal "GND1")
		(12 "In5.Cu" signal "IN1")
		(14 "In6.Cu" signal "GND2")
		(16 "In7.Cu" signal "IN2")
		(18 "In8.Cu" signal "GND3")
		(20 "In9.Cu" signal "IN3")
		(22 "In10.Cu" signal "GND4")
		(24 "In11.Cu" signal "IN4")
		(26 "In12.Cu" signal "GND5")
		(28 "In13.Cu" signal "IN5")
		(30 "In14.Cu" signal "GND6")
		(32 "In15.Cu" signal "IN6")
		(34 "In16.Cu" signal "GND7")
		(2 "B.Cu" signal "BOTTOM")
		(9 "F.Adhes" user "F.Adhesive")
		(11 "B.Adhes" user "B.Adhesive")
		(13 "F.Paste" user "Package Geometry/Pastemask Top")
		(15 "B.Paste" user "Package Geometry/Pastemask Bottom")
		(5 "F.SilkS" user "Ref Des/Silkscreen Top")
		(7 "B.SilkS" user "Ref Des/Silkscreen Bottom")
		(1 "F.Mask" user "Board Geometry/Soldermask Top")
		(3 "B.Mask" user "Board Geometry/Soldermask Bottom")
		(17 "Dwgs.User" user "User.Drawings")
		(19 "Cmts.User" user "User.Comments")
		(21 "Eco1.User" user "User.Eco1")
		(23 "Eco2.User" user "User.Eco2")
		(25 "Edge.Cuts" user "Board Geometry/Outline")
		(27 "Margin" user)
		(31 "F.CrtYd" user "Package Geometry/Place Bound Top")
		(29 "B.CrtYd" user "Package Geometry/Place Bound Bottom")
		(35 "F.Fab" user "Ref Des/Assembly Top")
		(33 "B.Fab" user "Ref Des/Assembly Bottom")
	)
	(footprint ""
		(layer "F.Cu")
		(at 146.253454 -291.390832)
		(property "Reference" "L108"
			(at 0 0 0)
			(layer "F.SilkS")
			(hide yes)
			(effects
				(font
					(size 1.27 1.27)
				)
			)
		)
		(property "Value" ""
			(at 0 0 0)
			(layer "F.Fab")
			(effects
				(font
					(size 1.27 1.27)
				)
			)
		)
		(duplicate_pad_numbers_are_jumpers no)
		(fp_line
			(start -1.63576 -0.8128)
			(end -1.63576 0.8128)
			(stroke
				(width 0.1524)
				(type default)
			)
			(layer "F.SilkS")
		)
		(fp_line
			(start -1.63576 -0.8128)
			(end 1.63576 -0.8128)
			(stroke
				(width 0.1524)
				(type default)
			)
			(layer "F.SilkS")
		)
		(fp_line
			(start 1.63576 -0.8128)
			(end 1.63576 0.8128)
			(stroke
				(width 0.1524)
				(type default)
			)
			(layer "F.SilkS")
		)
		(fp_line
			(start 1.63576 0.8128)
			(end -1.63576 0.8128)
			(stroke
				(width 0.1524)
				(type default)
			)
			(layer "F.SilkS")
		)
		(fp_line
			(start -1.56083 -0.738632)
			(end -1.56083 0.7366)
			(stroke
				(width 0.1)
				(type default)
			)
			(layer "F.Fab")
		)
		(fp_line
			(start -1.56083 0.7366)
			(end -1.524 0.7366)
			(stroke
				(width 0.1)
				(type default)
			)
			(layer "F.Fab")
		)
		(fp_line
			(start -1.524 0.7366)
			(end 1.524 0.7366)
			(stroke
				(width 0.1)
				(type default)
			)
			(layer "F.Fab")
		)
		(fp_line
			(start 1.524 0.7366)
			(end 1.560576 0.7366)
			(stroke
				(width 0.1)
				(type default)
			)
			(layer "F.Fab")
		)
		(fp_line
			(start 1.560576 -0.738632)
			(end -1.56083 -0.738632)
			(stroke
				(width 0.1)
				(type default)
			)
			(layer "F.Fab")
		)
		(fp_line
			(start 1.560576 0.7366)
			(end 1.560576 -0.738632)
			(stroke
				(width 0.1)
				(type default)
			)
			(layer "F.Fab")
		)
		(pad "1" smd rect
			(at -0.94996 0 180)
			(size 1.1176 1.3716)
			(layers "F.Cu" "F.Mask" "F.Paste")
			(net "P1V8_PLL0_PEX1")
		)
		(pad "2" smd rect
			(at 0.94996 0 180)
			(size 1.1176 1.3716)
			(layers "F.Cu" "F.Mask" "F.Paste")
			(net "PCEPLL4_VDDA18_PEX1")
		)
	)
	(footprint ""
		(layer "F.Cu")
		(at 162.775138 -56.977534 180)
		(property "Reference" "PC366"
			(at 0 0 180)
			(layer "F.SilkS")
			(hide yes)
			(effects
				(font
					(size 1.27 1.27)
				)
			)
		)
		(property "Value" ""
			(at 0 0 180)
			(layer "F.Fab")
			(effects
				(font
					(size 1.27 1.27)
				)
			)
		)
		(duplicate_pad_numbers_are_jumpers no)
		(fp_line
			(start 0.7874 0.4064)
			(end -0.7874 0.4064)
			(stroke
				(width 0.1524)
				(type default)
			)
			(layer "F.SilkS")
		)
		(fp_line
			(start 0.7874 -0.4064)
			(end 0.7874 0.4064)
			(stroke
				(width 0.1524)
				(type default)
			)
			(layer "F.SilkS")
		)
		(fp_line
			(start -0.7874 0.4064)
			(end -0.7874 -0.4064)
			(stroke
				(width 0.1524)
				(type default)
			)
			(layer "F.SilkS")
		)
		(fp_line
			(start -0.7874 -0.4064)
			(end 0.7874 -0.4064)
			(stroke
				(width 0.1524)
				(type default)
			)
			(layer "F.SilkS")
		)
		(fp_line
			(start 0.67945 0.3048)
			(end 0.120396 0.3048)
			(stroke
				(width 0.1)
				(type default)
			)
			(layer "F.Fab")
		)
		(fp_line
			(start 0.67945 -0.3048)
			(end 0.67945 0.3048)
			(stroke
				(width 0.1)
				(type default)
			)
			(layer "F.Fab")
		)
		(fp_line
			(start 0.12065 -0.2794)
			(end 0.12065 -0.3048)
			(stroke
				(width 0.1)
				(type default)
			)
			(layer "F.Fab")
		)
		(fp_line
			(start 0.12065 -0.3048)
			(end 0.67945 -0.3048)
			(stroke
				(width 0.1)
				(type default)
			)
			(layer "F.Fab")
		)
		(fp_line
			(start 0.120396 0.3048)
			(end 0.120396 0.2794)
			(stroke
				(width 0.1)
				(type default)
			)
			(layer "F.Fab")
		)
		(fp_line
			(start 0.120396 0.2794)
			(end -0.12065 0.2794)
			(stroke
				(width 0.1)
				(type default)
			)
			(layer "F.Fab")
		)
		(fp_line
			(start -0.12065 0.3048)
			(end -0.67945 0.3048)
			(stroke
				(width 0.1)
				(type default)
			)
			(layer "F.Fab")
		)
		(fp_line
			(start -0.12065 0.2794)
			(end -0.12065 0.3048)
			(stroke
				(width 0.1)
				(type default)
			)
			(layer "F.Fab")
		)
		(fp_line
			(start -0.12065 -0.2794)
			(end 0.12065 -0.2794)
			(stroke
				(width 0.1)
				(type default)
			)
			(layer "F.Fab")
		)
		(fp_line
			(start -0.12065 -0.305054)
			(end -0.12065 -0.2794)
			(stroke
				(width 0.1)
				(type default)
			)
			(layer "F.Fab")
		)
		(fp_line
			(start -0.67945 0.3048)
			(end -0.67945 -0.305054)
			(stroke
				(width 0.1)
				(type default)
			)
			(layer "F.Fab")
		)
		(fp_line
			(start -0.67945 -0.305054)
			(end -0.12065 -0.305054)
			(stroke
				(width 0.1)
				(type default)
			)
			(layer "F.Fab")
		)
		(pad "1" smd circle
			(at -0.40005 0 180)
			(size 0 0)
			(layers "F.Cu" "F.Mask" "F.Paste")
			(net "P12V_AUX")
		)
		(pad "2" smd circle
			(at 0.40005 0 180)
			(size 0 0)
			(layers "F.Cu" "F.Mask" "F.Paste")
			(net "GND")
		)
	)
	(footprint ""
		(layer "F.Cu")
		(at 430.961546 -131.686808 180)
		(property "Reference" "C655"
			(at 0 0 180)
			(layer "F.SilkS")
			(hide yes)
			(effects
				(font
					(size 1.27 1.27)
				)
			)
		)
		(property "Value" ""
			(at 0 0 180)
			(layer "F.Fab")
			(effects
				(font
					(size 1.27 1.27)
				)
			)
		)
		(duplicate_pad_numbers_are_jumpers no)
		(fp_line
			(start 0.299974 0.150114)
			(end -0.299974 0.150114)
			(stroke
				(width 0.1)
				(type default)
			)
			(layer "F.Fab")
		)
		(fp_line
			(start 0.299974 -0.150114)
			(end 0.299974 0.150114)
			(stroke
				(width 0.1)
				(type default)
			)
			(layer "F.Fab")
		)
		(fp_line
			(start -0.299974 0.150114)
			(end -0.299974 -0.150114)
			(stroke
				(width 0.1)
				(type default)
			)
			(layer "F.Fab")
		)
		(fp_line
			(start -0.299974 -0.150114)
			(end 0.299974 -0.150114)
			(stroke
				(width 0.1)
				(type default)
			)
			(layer "F.Fab")
		)
		(pad "1" smd rect
			(at -0.2667 0 180)
			(size 0.3048 0.381)
			(layers "F.Cu" "F.Mask" "F.Paste")
			(net "P5E_PEX3_STN0_TX_DN<5>")
		)
		(pad "2" smd rect
			(at 0.2667 0 180)
			(size 0.3048 0.381)
			(layers "F.Cu" "F.Mask" "F.Paste")
			(net "P5E_PEX3_STN0_TX_C_DN<5>")
		)
	)
	(footprint ""
		(layer "F.Cu")
		(at 112.198404 -166.252652)
		(property "Reference" "PC27"
			(at 0 0 0)
			(layer "F.SilkS")
			(hide yes)
			(effects
				(font
					(size 1.27 1.27)
				)
			)
		)
		(property "Value" ""
			(at 0 0 0)
			(layer "F.Fab")
			(effects
				(font
					(size 1.27 1.27)
				)
			)
		)
		(duplicate_pad_numbers_are_jumpers no)
		(fp_line
			(start -1.524 -0.762)
			(end 1.524 -0.762)
			(stroke
				(width 0.1524)
				(type default)
			)
			(layer "F.SilkS")
		)
		(fp_line
			(start -1.524 0.762)
			(end -1.524 -0.762)
			(stroke
				(width 0.1524)
				(type default)
			)
			(layer "F.SilkS")
		)
		(fp_line
			(start 1.524 -0.762)
			(end 1.524 0.762)
			(stroke
				(width 0.1524)
				(type default)
			)
			(layer "F.SilkS")
		)
		(fp_line
			(start 1.524 0.762)
			(end -1.524 0.762)
			(stroke
				(width 0.1524)
				(type default)
			)
			(layer "F.SilkS")
		)
		(fp_line
			(start -1.1049 -0.724916)
			(end -1.1049 0.724916)
			(stroke
				(width 0.1)
				(type default)
			)
			(layer "F.Fab")
		)
		(fp_line
			(start -1.1049 0.724916)
			(end 1.1049 0.724916)
			(stroke
				(width 0.1)
				(type default)
			)
			(layer "F.Fab")
		)
		(fp_line
			(start 1.1049 -0.724916)
			(end -1.1049 -0.724916)
			(stroke
				(width 0.1)
				(type default)
			)
			(layer "F.Fab")
		)
		(fp_line
			(start 1.1049 0.724916)
			(end 1.1049 -0.724916)
			(stroke
				(width 0.1)
				(type default)
			)
			(layer "F.Fab")
		)
		(pad "1" smd rect
			(at -0.889 0 180)
			(size 1.016 1.27)
			(layers "F.Cu" "F.Mask" "F.Paste")
			(net "SW_P12V_P3V3_AUX_FLT")
		)
		(pad "2" smd rect
			(at 0.889 0 180)
			(size 1.016 1.27)
			(layers "F.Cu" "F.Mask" "F.Paste")
			(net "GND")
		)
	)
	(footprint ""
		(layer "F.Cu")
		(at 328.022204 -343.952322 90)
		(property "Reference" "C535"
			(at 0 0 90)
			(layer "F.SilkS")
			(hide yes)
			(effects
				(font
					(size 1.27 1.27)
				)
			)
		)
		(property "Value" ""
			(at 0 0 90)
			(layer "F.Fab")
			(effects
				(font
					(size 1.27 1.27)
				)
			)
		)
		(duplicate_pad_numbers_are_jumpers no)
		(fp_line
			(start 0.299974 -0.150114)
			(end 0.299974 0.150114)
			(stroke
				(width 0.1)
				(type default)
			)
			(layer "F.Fab")
		)
		(fp_line
			(start -0.299974 -0.150114)
			(end 0.299974 -0.150114)
			(stroke
				(width 0.1)
				(type default)
			)
			(layer "F.Fab")
		)
		(fp_line
			(start 0.299974 0.150114)
			(end -0.299974 0.150114)
			(stroke
				(width 0.1)
				(type default)
			)
			(layer "F.Fab")
		)
		(fp_line
			(start -0.299974 0.150114)
			(end -0.299974 -0.150114)
			(stroke
				(width 0.1)
				(type default)
			)
			(layer "F.Fab")
		)
		(pad "1" smd rect
			(at -0.2667 0 90)
			(size 0.3048 0.381)
			(layers "F.Cu" "F.Mask" "F.Paste")
			(net "P5E_PEX2_STN5_TX_DP<87>")
		)
		(pad "2" smd rect
			(at 0.2667 0 90)
			(size 0.3048 0.381)
			(layers "F.Cu" "F.Mask" "F.Paste")
			(net "P5E_PEX2_STN5_TX_C_DP<87>")
		)
	)
	(footprint ""
		(layer "F.Cu")
		(at 376.312684 -91.1098)
		(property "Reference" "R1749"
			(at 0 0 0)
			(layer "F.SilkS")
			(hide yes)
			(effects
				(font
					(size 1.27 1.27)
				)
			)
		)
		(property "Value" ""
			(at 0 0 0)
			(layer "F.Fab")
			(effects
				(font
					(size 1.27 1.27)
				)
			)
		)
		(duplicate_pad_numbers_are_jumpers no)
		(fp_line
			(start -0.7874 -0.4064)
			(end 0.7874 -0.4064)
			(stroke
				(width 0.1524)
				(type default)
			)
			(layer "F.SilkS")
		)
		(fp_line
			(start -0.7874 0.4064)
			(end -0.7874 -0.4064)
			(stroke
				(width 0.1524)
				(type default)
			)
			(layer "F.SilkS")
		)
		(fp_line
			(start 0.7874 -0.4064)
			(end 0.7874 0.4064)
			(stroke
				(width 0.1524)
				(type default)
			)
			(layer "F.SilkS")
		)
		(fp_line
			(start 0.7874 0.4064)
			(end -0.7874 0.4064)
			(stroke
				(width 0.1524)
				(type default)
			)
			(layer "F.SilkS")
		)
		(fp_line
			(start -0.67945 -0.305054)
			(end -0.12065 -0.305054)
			(stroke
				(width 0.1)
				(type default)
			)
			(layer "F.Fab")
		)
		(fp_line
			(start -0.67945 0.3048)
			(end -0.67945 -0.305054)
			(stroke
				(width 0.1)
				(type default)
			)
			(layer "F.Fab")
		)
		(fp_line
			(start -0.12065 -0.305054)
			(end -0.12065 -0.2794)
			(stroke
				(width 0.1)
				(type default)
			)
			(layer "F.Fab")
		)
		(fp_line
			(start -0.12065 -0.2794)
			(end 0.12065 -0.2794)
			(stroke
				(width 0.1)
				(type default)
			)
			(layer "F.Fab")
		)
		(fp_line
			(start -0.12065 0.2794)
			(end -0.12065 0.3048)
			(stroke
				(width 0.1)
				(type default)
			)
			(layer "F.Fab")
		)
		(fp_line
			(start -0.12065 0.3048)
			(end -0.67945 0.3048)
			(stroke
				(width 0.1)
				(type default)
			)
			(layer "F.Fab")
		)
		(fp_line
			(start 0.120396 0.2794)
			(end -0.12065 0.2794)
			(stroke
				(width 0.1)
				(type default)
			)
			(layer "F.Fab")
		)
		(fp_line
			(start 0.120396 0.3048)
			(end 0.120396 0.2794)
			(stroke
				(width 0.1)
				(type default)
			)
			(layer "F.Fab")
		)
		(fp_line
			(start 0.12065 -0.3048)
			(end 0.67945 -0.3048)
			(stroke
				(width 0.1)
				(type default)
			)
			(layer "F.Fab")
		)
		(fp_line
			(start 0.12065 -0.2794)
			(end 0.12065 -0.3048)
			(stroke
				(width 0.1)
				(type default)
			)
			(layer "F.Fab")
		)
		(fp_line
			(start 0.67945 -0.3048)
			(end 0.67945 0.3048)
			(stroke
				(width 0.1)
				(type default)
			)
			(layer "F.Fab")
		)
		(fp_line
			(start 0.67945 0.3048)
			(end 0.120396 0.3048)
			(stroke
				(width 0.1)
				(type default)
			)
			(layer "F.Fab")
		)
		(pad "1" smd circle
			(at -0.40005 0)
			(size 0 0)
			(layers "F.Cu" "F.Mask" "F.Paste")
			(net "P3V3_AUX")
		)
		(pad "2" smd circle
			(at 0.40005 0)
			(size 0 0)
			(layers "F.Cu" "F.Mask" "F.Paste")
			(net "BIC_I2C6_MUX_A0")
		)
	)
	(footprint ""
		(layer "F.Cu")
		(at 147.80006 -407.960068 180)
		(property "Reference" "J64"
			(at 0.590042 -11.910568 0)
			(unlocked yes)
			(layer "F.SilkS")
			(effects
				(font
					(size 0.7874 0.5842)
					(thickness 0.1524)
				)
			)
		)
		(property "Value" ""
			(at 0 0 180)
			(layer "F.Fab")
			(effects
				(font
					(size 1.27 1.27)
				)
			)
		)
		(duplicate_pad_numbers_are_jumpers no)
		(fp_line
			(start 3.525012 21.310092)
			(end 3.525012 -10.489946)
			(stroke
				(width 0.1524)
				(type default)
			)
			(layer "F.SilkS")
		)
		(fp_line
			(start 3.525012 -10.489946)
			(end -3.525012 -10.489946)
			(stroke
				(width 0.1524)
				(type default)
			)
			(layer "F.SilkS")
		)
		(fp_line
			(start -3.525012 21.310092)
			(end 3.525012 21.310092)
			(stroke
				(width 0.1524)
				(type default)
			)
			(layer "F.SilkS")
		)
		(fp_line
			(start -3.525012 10.6299)
			(end 3.525012 10.6299)
			(stroke
				(width 0.1524)
				(type default)
			)
			(layer "F.SilkS")
		)
		(fp_line
			(start -3.525012 -10.489946)
			(end -3.525012 21.310092)
			(stroke
				(width 0.1524)
				(type default)
			)
			(layer "F.SilkS")
		)
		(fp_line
			(start 3.525012 21.310092)
			(end 3.525012 -10.489946)
			(stroke
				(width 0.1)
				(type default)
			)
			(layer "F.Fab")
		)
		(fp_line
			(start 3.525012 -10.489946)
			(end -3.525012 -10.489946)
			(stroke
				(width 0.1)
				(type default)
			)
			(layer "F.Fab")
		)
		(fp_line
			(start -3.525012 21.310092)
			(end 3.525012 21.310092)
			(stroke
				(width 0.1)
				(type default)
			)
			(layer "F.Fab")
		)
		(fp_line
			(start -3.525012 -10.489946)
			(end -3.525012 21.310092)
			(stroke
				(width 0.1)
				(type default)
			)
			(layer "F.Fab")
		)
		(pad "" np_thru_hole circle
			(at 0 -6.620002 180)
			(size 3.175 3.175)
			(drill 3.175)
			(layers "*.Cu" "*.Mask")
			(clearance 0.381)
			(thermal_gap 0.381)
		)
		(pad "" np_thru_hole circle
			(at 0 0 180)
			(size 0 0)
			(drill 3.175)
			(layers "*.Cu" "*.Mask")
			(clearance 0)
		)
		(pad "" np_thru_hole circle
			(at 0 5.130038 180)
			(size 3.175 3.175)
			(drill 3.175)
			(layers "*.Cu" "*.Mask")
			(clearance 0.381)
			(thermal_gap 0.381)
		)
		(zone
			(layers "F.Cu" "B.Cu" "In1.Cu" "In2.Cu" "In3.Cu" "In4.Cu" "In5.Cu" "In6.Cu"
				"In7.Cu" "In8.Cu" "In9.Cu" "In10.Cu" "In11.Cu" "In12.Cu" "In13.Cu" "In14.Cu"
				"In15.Cu" "In16.Cu"
			)
			(hatch none 0.5)
			(connect_pads
				(clearance 0)
			)
			(min_thickness 0.25)
			(keepout
				(tracks not_allowed)
				(vias allowed)
				(pads allowed)
				(copperpour not_allowed)
				(footprints allowed)
			)
			(placement
				(enabled no)
				(sheetname "")
			)
			(fill
				(thermal_gap 0.5)
				(thermal_bridge_width 0.5)
				(island_removal_mode 0)
			)
			(polygon
				(pts
					(arc
						(start 149.89556 -413.090106)
						(mid 145.70456 -413.090106)
						(end 149.89556 -413.090106)
					)
				)
			)
		)
		(zone
			(layers "F.Cu" "B.Cu" "In1.Cu" "In2.Cu" "In3.Cu" "In4.Cu" "In5.Cu" "In6.Cu"
				"In7.Cu" "In8.Cu" "In9.Cu" "In10.Cu" "In11.Cu" "In12.Cu" "In13.Cu" "In14.Cu"
				"In15.Cu" "In16.Cu"
			)
			(hatch none 0.5)
			(connect_pads
				(clearance 0)
			)
			(min_thickness 0.25)
			(keepout
				(tracks not_allowed)
				(vias allowed)
				(pads allowed)
				(copperpour not_allowed)
				(footprints allowed)
			)
			(placement
				(enabled no)
				(sheetname "")
			)
			(fill
				(thermal_gap 0.5)
				(thermal_bridge_width 0.5)
				(island_removal_mode 0)
			)
			(polygon
				(pts
					(arc
						(start 149.89556 -401.340066)
						(mid 145.70456 -401.340066)
						(end 149.89556 -401.340066)
					)
				)
			)
		)
		(zone
			(layers "F.Cu" "B.Cu" "In1.Cu" "In2.Cu" "In3.Cu" "In4.Cu" "In5.Cu" "In6.Cu"
				"In7.Cu" "In8.Cu" "In9.Cu" "In10.Cu" "In11.Cu" "In12.Cu" "In13.Cu" "In14.Cu"
				"In15.Cu" "In16.Cu"
			)
			(hatch none 0.5)
			(connect_pads
				(clearance 0)
			)
			(min_thickness 0.25)
			(keepout
				(tracks not_allowed)
				(vias allowed)
				(pads allowed)
				(copperpour not_allowed)
				(footprints allowed)
			)
			(placement
				(enabled no)
				(sheetname "")
			)
			(fill
				(thermal_gap 0.5)
				(thermal_bridge_width 0.5)
				(island_removal_mode 0)
			)
			(polygon
				(pts
					(arc
						(start 151.41956 -407.960068)
						(mid 144.18056 -407.960068)
						(end 151.41956 -407.960068)
					)
				)
			)
		)
	)
	(footprint ""
		(layer "F.Cu")
		(at 5.65023 -50.96383 180)
		(property "Reference" "PC501"
			(at 0 0 180)
			(layer "F.SilkS")
			(hide yes)
			(effects
				(font
					(size 1.27 1.27)
				)
			)
		)
		(property "Value" ""
			(at 0 0 180)
			(layer "F.Fab")
			(effects
				(font
					(size 1.27 1.27)
				)
			)
		)
		(duplicate_pad_numbers_are_jumpers no)
		(fp_line
			(start 1.524 0.762)
			(end -1.524 0.762)
			(stroke
				(width 0.1524)
				(type default)
			)
			(layer "F.SilkS")
		)
		(fp_line
			(start 1.524 -0.762)
			(end 1.524 0.762)
			(stroke
				(width 0.1524)
				(type default)
			)
			(layer "F.SilkS")
		)
		(fp_line
			(start -1.524 0.762)
			(end -1.524 -0.762)
			(stroke
				(width 0.1524)
				(type default)
			)
			(layer "F.SilkS")
		)
		(fp_line
			(start -1.524 -0.762)
			(end 1.524 -0.762)
			(stroke
				(width 0.1524)
				(type default)
			)
			(layer "F.SilkS")
		)
		(fp_line
			(start 1.1049 0.724916)
			(end 1.1049 -0.724916)
			(stroke
				(width 0.1)
				(type default)
			)
			(layer "F.Fab")
		)
		(fp_line
			(start 1.1049 -0.724916)
			(end -1.1049 -0.724916)
			(stroke
				(width 0.1)
				(type default)
			)
			(layer "F.Fab")
		)
		(fp_line
			(start -1.1049 0.724916)
			(end 1.1049 0.724916)
			(stroke
				(width 0.1)
				(type default)
			)
			(layer "F.Fab")
		)
		(fp_line
			(start -1.1049 -0.724916)
			(end -1.1049 0.724916)
			(stroke
				(width 0.1)
				(type default)
			)
			(layer "F.Fab")
		)
		(pad "1" smd rect
			(at -0.889 0)
			(size 1.016 1.27)
			(layers "F.Cu" "F.Mask" "F.Paste")
			(net "P3V3_SSD0")
		)
		(pad "2" smd rect
			(at 0.889 0)
			(size 1.016 1.27)
			(layers "F.Cu" "F.Mask" "F.Paste")
			(net "GND")
		)
	)
)
